(kicad_pcb
	(version 20241229)
	(generator "pcbnew")
	(generator_version "9.0")
	(general
		(thickness 1.294)
		(legacy_teardrops no)
	)
	(paper "A3")
	(title_block
		(title "Kintex 410T devboard")
		(date "2024-04-03")
		(rev "1.1.2")
		(comment 9 "footprints 702-707 of 975")
	)
	(layers
		(0 "F.Cu" mixed)
		(4 "In1.Cu" power)
		(6 "In2.Cu" power)
		(8 "In3.Cu" mixed)
		(10 "In4.Cu" power)
		(12 "In5.Cu" mixed)
		(14 "In6.Cu" power)
		(16 "In7.Cu" mixed)
		(18 "In8.Cu" power)
		(2 "B.Cu" mixed)
		(9 "F.Adhes" user "F.Adhesive")
		(11 "B.Adhes" user "B.Adhesive")
		(13 "F.Paste" user)
		(15 "B.Paste" user)
		(5 "F.SilkS" user "F.Silkscreen")
		(7 "B.SilkS" user "B.Silkscreen")
		(1 "F.Mask" user)
		(3 "B.Mask" user)
		(17 "Dwgs.User" user "User.Drawings")
		(19 "Cmts.User" user "User.Comments")
		(21 "Eco1.User" user "User.Eco1")
		(23 "Eco2.User" user "User.Eco2")
		(25 "Edge.Cuts" user)
		(27 "Margin" user)
		(31 "F.CrtYd" user "F.Courtyard")
		(29 "B.CrtYd" user "B.Courtyard")
		(35 "F.Fab" user)
		(33 "B.Fab" user)
	)
	(footprint "antmicro-footprints:C_0201"
		(layer "B.Cu")
		(at 188.000001 128.500001 180)
		(descr "Capacitor SMD 0201")
		(tags "capacitor SMD 0201")
		(property "Reference" "C147"
			(at 0.625001 -0.324999 0)
			(layer "B.SilkS")
			(effects
				(font
					(size 0.7 0.7)
					(thickness 0.15)
				)
				(justify left bottom mirror)
			)
		)
		(property "Value" "C_100n_0201"
			(at 0 -1.4 0)
			(layer "B.Fab")
			(effects
				(font
					(size 0.7 0.7)
					(thickness 0.15)
				)
				(justify left bottom mirror)
			)
		)
		(property "Description" "SMD Multilayer Ceramic Capacitor, 0.1 µF, 6.3 V, 0201 [0603 Metric], ± 10%, X6S, CC Series"
			(at 0 0 180)
			(layer "F.Fab")
			(hide yes)
			(effects
				(font
					(size 1.27 1.27)
					(thickness 0.15)
				)
			)
		)
		(property "Author" "Antmicro"
			(at 376.000002 257.000002 0)
			(layer "B.Fab")
			(hide yes)
			(effects
				(font
					(size 1 1)
					(thickness 0.15)
				)
				(justify mirror)
			)
		)
		(property "Dielectric" ""
			(at 376.000002 257.000002 0)
			(layer "B.Fab")
			(hide yes)
			(effects
				(font
					(size 1 1)
					(thickness 0.15)
				)
				(justify mirror)
			)
		)
		(property "License" "Apache-2.0"
			(at 376.000002 257.000002 0)
			(layer "B.Fab")
			(hide yes)
			(effects
				(font
					(size 1 1)
					(thickness 0.15)
				)
				(justify mirror)
			)
		)
		(property "MPN" "CC0201KRX6S5BB104"
			(at 376.000002 257.000002 0)
			(layer "B.Fab")
			(hide yes)
			(effects
				(font
					(size 1 1)
					(thickness 0.15)
				)
				(justify mirror)
			)
		)
		(property "Manufacturer" "YAGEO"
			(at 376.000002 257.000002 0)
			(layer "B.Fab")
			(hide yes)
			(effects
				(font
					(size 1 1)
					(thickness 0.15)
				)
				(justify mirror)
			)
		)
		(property "Val" "100n"
			(at 376.000002 257.000002 0)
			(layer "B.Fab")
			(hide yes)
			(effects
				(font
					(size 1 1)
					(thickness 0.15)
				)
				(justify mirror)
			)
		)
		(property "Voltage" ""
			(at 376.000002 257.000002 0)
			(layer "B.Fab")
			(hide yes)
			(effects
				(font
					(size 1 1)
					(thickness 0.15)
				)
				(justify mirror)
			)
		)
		(sheetname "FPGA supply")
		(sheetfile "fpga-supply.kicad_sch")
		(attr smd)
		(fp_rect
			(start -0.7 0.35)
			(end 0.7 -0.35)
			(stroke
				(width 0.05)
				(type default)
			)
			(fill no)
			(layer "B.CrtYd")
		)
		(fp_rect
			(start 0.3 -0.15)
			(end -0.301 0.149)
			(stroke
				(width 0.15)
				(type solid)
			)
			(fill no)
			(layer "B.Fab")
		)
		(pad "" smd roundrect
			(at -0.349 0.002 180)
			(size 0.318 0.36)
			(layers "B.Paste")
			(roundrect_rratio 0.25)
		)
		(pad "" smd roundrect
			(at 0.341 0.002 180)
			(size 0.318 0.36)
			(layers "B.Paste")
			(roundrect_rratio 0.25)
		)
		(pad "1" smd roundrect
			(at -0.321 0.002 180)
			(size 0.46 0.4)
			(layers "B.Cu" "B.Mask")
			(roundrect_rratio 0.25)
			(net 1 "GND")
			(pintype "passive")
		)
		(pad "2" smd roundrect
			(at 0.32 0.002 180)
			(size 0.46 0.4)
			(layers "B.Cu" "B.Mask")
			(roundrect_rratio 0.25)
			(net 8 "+1V2_MGTAVTT")
			(pintype "passive")
		)
	)
	(footprint "antmicro-footprints:C_0603_1608Metric"
		(layer "B.Cu")
		(at 230.45 165.2 90)
		(descr "Capacitor SMD 0603")
		(tags "capacitor 0603")
		(property "Reference" "C191"
			(at 3.975 0.4 270)
			(layer "B.SilkS")
			(effects
				(font
					(size 0.7 0.7)
					(thickness 0.15)
				)
				(justify left bottom mirror)
			)
		)
		(property "Value" "C_1u_25V_0603"
			(at 0 -1.6 270)
			(layer "B.Fab")
			(effects
				(font
					(size 0.7 0.7)
					(thickness 0.15)
				)
				(justify left bottom mirror)
			)
		)
		(property "Description" "SMD Multilayer Ceramic Capacitor, 1 µF, 25 V, 0603 [1608 Metric], ± 10%, X5R, CL"
			(at 0 0 90)
			(layer "F.Fab")
			(hide yes)
			(effects
				(font
					(size 1.27 1.27)
					(thickness 0.15)
				)
			)
		)
		(property "Author" "Antmicro"
			(at 395.65 -65.25 0)
			(layer "B.Fab")
			(hide yes)
			(effects
				(font
					(size 1 1)
					(thickness 0.15)
				)
				(justify mirror)
			)
		)
		(property "Dielectric" ""
			(at 395.65 -65.25 0)
			(layer "B.Fab")
			(hide yes)
			(effects
				(font
					(size 1 1)
					(thickness 0.15)
				)
				(justify mirror)
			)
		)
		(property "License" "Apache-2.0"
			(at 395.65 -65.25 0)
			(layer "B.Fab")
			(hide yes)
			(effects
				(font
					(size 1 1)
					(thickness 0.15)
				)
				(justify mirror)
			)
		)
		(property "MPN" "CL10A105KA8NNNC"
			(at 395.65 -65.25 0)
			(layer "B.Fab")
			(hide yes)
			(effects
				(font
					(size 1 1)
					(thickness 0.15)
				)
				(justify mirror)
			)
		)
		(property "Manufacturer" "Samsung Electro-Mechanics"
			(at 395.65 -65.25 0)
			(layer "B.Fab")
			(hide yes)
			(effects
				(font
					(size 1 1)
					(thickness 0.15)
				)
				(justify mirror)
			)
		)
		(property "Val" "1u"
			(at 395.65 -65.25 0)
			(layer "B.Fab")
			(hide yes)
			(effects
				(font
					(size 1 1)
					(thickness 0.15)
				)
				(justify mirror)
			)
		)
		(property "Voltage" "25V"
			(at 395.65 -65.25 0)
			(layer "B.Fab")
			(hide yes)
			(effects
				(font
					(size 1 1)
					(thickness 0.15)
				)
				(justify mirror)
			)
		)
		(sheetname "Power supply")
		(sheetfile "power-supply.kicad_sch")
		(attr smd)
		(fp_line
			(start -0.15 -0.4)
			(end 0.15 -0.4)
			(stroke
				(width 0.15)
				(type solid)
			)
			(layer "B.SilkS")
		)
		(fp_line
			(start -0.15 0.4)
			(end 0.15 0.4)
			(stroke
				(width 0.15)
				(type solid)
			)
			(layer "B.SilkS")
		)
		(fp_rect
			(start -1.25 0.65)
			(end 1.25 -0.65)
			(stroke
				(width 0.05)
				(type solid)
			)
			(fill no)
			(layer "B.CrtYd")
		)
		(fp_rect
			(start -0.8 0.4)
			(end 0.8 -0.4)
			(stroke
				(width 0.15)
				(type solid)
			)
			(fill no)
			(layer "B.Fab")
		)
		(pad "1" smd roundrect
			(at -0.7 0 90)
			(size 0.8 1)
			(layers "B.Cu" "B.Mask" "B.Paste")
			(roundrect_rratio 0.2)
			(net 5 "/Power supply/PD_VBUS")
			(pintype "passive")
		)
		(pad "2" smd roundrect
			(at 0.7 0 90)
			(size 0.8 1)
			(layers "B.Cu" "B.Mask" "B.Paste")
			(roundrect_rratio 0.2)
			(net 1 "GND")
			(pintype "passive")
		)
	)
	(footprint "antmicro-footprints:R_0402_1005Metric"
		(layer "B.Cu")
		(at 170 144.625 180)
		(descr "Resistor SMD 0402")
		(tags "resistor SMD 0402")
		(property "Reference" "R43"
			(at -3.025 -1.425 0)
			(layer "B.SilkS")
			(effects
				(font
					(size 0.7 0.7)
					(thickness 0.15)
				)
				(justify left bottom mirror)
			)
		)
		(property "Value" "R_40R2_0402"
			(at 0 -1.4 0)
			(layer "B.Fab")
			(effects
				(font
					(size 0.7 0.7)
					(thickness 0.15)
				)
				(justify left bottom mirror)
			)
		)
		(property "Description" "SMD Chip Resistor, Ceramic, 40.2 ohm, ± 1%, 62.5 mW, 0402 [1005 Metric], Thick Film"
			(at 0 0 180)
			(layer "F.Fab")
			(hide yes)
			(effects
				(font
					(size 1.27 1.27)
					(thickness 0.15)
				)
			)
		)
		(property "Author" "Antmicro"
			(at 340 289.25 0)
			(layer "B.Fab")
			(hide yes)
			(effects
				(font
					(size 1 1)
					(thickness 0.15)
				)
				(justify mirror)
			)
		)
		(property "License" "Apache-2.0"
			(at 340 289.25 0)
			(layer "B.Fab")
			(hide yes)
			(effects
				(font
					(size 1 1)
					(thickness 0.15)
				)
				(justify mirror)
			)
		)
		(property "MPN" "CR0402-FX-40R2GLF"
			(at 340 289.25 0)
			(layer "B.Fab")
			(hide yes)
			(effects
				(font
					(size 1 1)
					(thickness 0.15)
				)
				(justify mirror)
			)
		)
		(property "Manufacturer" "Bourns"
			(at 340 289.25 0)
			(layer "B.Fab")
			(hide yes)
			(effects
				(font
					(size 1 1)
					(thickness 0.15)
				)
				(justify mirror)
			)
		)
		(property "Tolerance" "1%"
			(at 340 289.25 0)
			(layer "B.Fab")
			(hide yes)
			(effects
				(font
					(size 1 1)
					(thickness 0.15)
				)
				(justify mirror)
			)
		)
		(property "Val" "40R2"
			(at 340 289.25 0)
			(layer "B.Fab")
			(hide yes)
			(effects
				(font
					(size 1 1)
					(thickness 0.15)
				)
				(justify mirror)
			)
		)
		(sheetname "DRAM + SRAM")
		(sheetfile "ram.kicad_sch")
		(attr smd)
		(fp_rect
			(start -0.925 0.47)
			(end 0.925 -0.47)
			(stroke
				(width 0.05)
				(type default)
			)
			(fill no)
			(layer "B.CrtYd")
		)
		(fp_rect
			(start -0.5 0.25)
			(end 0.5 -0.25)
			(stroke
				(width 0.15)
				(type solid)
			)
			(fill no)
			(layer "B.Fab")
		)
		(pad "1" smd roundrect
			(at -0.48 0 180)
			(size 0.59 0.64)
			(layers "B.Cu" "B.Mask" "B.Paste")
			(roundrect_rratio 0.25)
			(net 560 "/DRAM + SRAM/DDR.~{RAS}")
			(pintype "passive")
		)
		(pad "2" smd roundrect
			(at 0.48 0 180)
			(size 0.59 0.64)
			(layers "B.Cu" "B.Mask" "B.Paste")
			(roundrect_rratio 0.25)
			(net 7 "+0V675_VTT")
			(pintype "passive")
		)
	)
	(footprint "antmicro-footprints:C_0402_1005Metric"
		(layer "B.Cu")
		(at 196.4 134.175 180)
		(descr "Capacitor SMD 0402")
		(tags "capacitor SMD 0402")
		(property "Reference" "C59"
			(at -25.1 28.075 0)
			(layer "B.SilkS")
			(effects
				(font
					(size 0.7 0.7)
					(thickness 0.15)
				)
				(justify left bottom mirror)
			)
		)
		(property "Value" "C_100n_0402"
			(at 0 -1.169 0)
			(layer "B.Fab")
			(effects
				(font
					(size 0.7 0.7)
					(thickness 0.15)
				)
				(justify left bottom mirror)
			)
		)
		(property "Description" "SMD Multilayer Ceramic Capacitor, 0.1 µF, 50 V, 0402 [1005 Metric], ± 10%, X5R, GRM Series"
			(at 0 0 180)
			(layer "F.Fab")
			(hide yes)
			(effects
				(font
					(size 1.27 1.27)
					(thickness 0.15)
				)
			)
		)
		(property "Author" "Antmicro"
			(at 392.8 268.35 0)
			(layer "B.Fab")
			(hide yes)
			(effects
				(font
					(size 1 1)
					(thickness 0.15)
				)
				(justify mirror)
			)
		)
		(property "Dielectric" "X5R"
			(at 392.8 268.35 0)
			(layer "B.Fab")
			(hide yes)
			(effects
				(font
					(size 1 1)
					(thickness 0.15)
				)
				(justify mirror)
			)
		)
		(property "License" "Apache-2.0"
			(at 392.8 268.35 0)
			(layer "B.Fab")
			(hide yes)
			(effects
				(font
					(size 1 1)
					(thickness 0.15)
				)
				(justify mirror)
			)
		)
		(property "MPN" "GRM155R61H104KE14D"
			(at 392.8 268.35 0)
			(layer "B.Fab")
			(hide yes)
			(effects
				(font
					(size 1 1)
					(thickness 0.15)
				)
				(justify mirror)
			)
		)
		(property "Manufacturer" "Murata"
			(at 392.8 268.35 0)
			(layer "B.Fab")
			(hide yes)
			(effects
				(font
					(size 1 1)
					(thickness 0.15)
				)
				(justify mirror)
			)
		)
		(property "Val" "100n"
			(at 392.8 268.35 0)
			(layer "B.Fab")
			(hide yes)
			(effects
				(font
					(size 1 1)
					(thickness 0.15)
				)
				(justify mirror)
			)
		)
		(property "Voltage" "50V"
			(at 392.8 268.35 0)
			(layer "B.Fab")
			(hide yes)
			(effects
				(font
					(size 1 1)
					(thickness 0.15)
				)
				(justify mirror)
			)
		)
		(sheetname "FPGA supply")
		(sheetfile "fpga-supply.kicad_sch")
		(attr smd)
		(fp_rect
			(start -0.925 0.47)
			(end 0.925 -0.47)
			(stroke
				(width 0.05)
				(type default)
			)
			(fill no)
			(layer "B.CrtYd")
		)
		(fp_line
			(start 0.504 0.25)
			(end 0.504 -0.248)
			(stroke
				(width 0.15)
				(type solid)
			)
			(layer "B.Fab")
		)
		(fp_line
			(start 0.504 -0.248)
			(end -0.494 -0.248)
			(stroke
				(width 0.15)
				(type solid)
			)
			(layer "B.Fab")
		)
		(fp_line
			(start -0.494 0.25)
			(end 0.504 0.25)
			(stroke
				(width 0.15)
				(type solid)
			)
			(layer "B.Fab")
		)
		(fp_line
			(start -0.494 -0.248)
			(end -0.494 0.25)
			(stroke
				(width 0.15)
				(type solid)
			)
			(layer "B.Fab")
		)
		(pad "1" smd roundrect
			(at -0.48 0 180)
			(size 0.59 0.64)
			(layers "B.Cu" "B.Mask" "B.Paste")
			(roundrect_rratio 0.25)
			(net 1 "GND")
			(pintype "passive")
		)
		(pad "2" smd roundrect
			(at 0.48 0 180)
			(size 0.59 0.64)
			(layers "B.Cu" "B.Mask" "B.Paste")
			(roundrect_rratio 0.25)
			(net 26 "+1V8")
			(pintype "passive")
		)
	)
	(footprint "antmicro-footprints:R_0402_1005Metric"
		(layer "B.Cu")
		(at 258.4 81.4 -90)
		(descr "Resistor SMD 0402")
		(tags "resistor SMD 0402")
		(property "Reference" "R360"
			(at -1.25 0.525 90)
			(layer "B.SilkS")
			(effects
				(font
					(size 0.7 0.7)
					(thickness 0.15)
				)
				(justify left bottom mirror)
			)
		)
		(property "Value" "R_100k_0402"
			(at 0 -1.4 90)
			(layer "B.Fab")
			(effects
				(font
					(size 0.7 0.7)
					(thickness 0.15)
				)
				(justify left bottom mirror)
			)
		)
		(property "Description" "SMD Chip Resistor, 100 kohm, ± 1%, 62.5 mW, 0402 [1005 Metric], Thick Film, General Purpose"
			(at 0 0 270)
			(layer "F.Fab")
			(hide yes)
			(effects
				(font
					(size 1.27 1.27)
					(thickness 0.15)
				)
			)
		)
		(property "Author" "Antmicro"
			(at 177 339.8 0)
			(layer "B.Fab")
			(hide yes)
			(effects
				(font
					(size 1 1)
					(thickness 0.15)
				)
				(justify mirror)
			)
		)
		(property "License" "Apache-2.0"
			(at 177 339.8 0)
			(layer "B.Fab")
			(hide yes)
			(effects
				(font
					(size 1 1)
					(thickness 0.15)
				)
				(justify mirror)
			)
		)
		(property "MPN" "CR0402-FX-1003GLF"
			(at 177 339.8 0)
			(layer "B.Fab")
			(hide yes)
			(effects
				(font
					(size 1 1)
					(thickness 0.15)
				)
				(justify mirror)
			)
		)
		(property "Manufacturer" "Bourns"
			(at 177 339.8 0)
			(layer "B.Fab")
			(hide yes)
			(effects
				(font
					(size 1 1)
					(thickness 0.15)
				)
				(justify mirror)
			)
		)
		(property "Tolerance" "1%"
			(at 177 339.8 0)
			(layer "B.Fab")
			(hide yes)
			(effects
				(font
					(size 1 1)
					(thickness 0.15)
				)
				(justify mirror)
			)
		)
		(property "Val" "100k"
			(at 177 339.8 0)
			(layer "B.Fab")
			(hide yes)
			(effects
				(font
					(size 1 1)
					(thickness 0.15)
				)
				(justify mirror)
			)
		)
		(sheetname "User GPIO + LED + button + DIP switch")
		(sheetfile "user-gpio.kicad_sch")
		(attr smd)
		(fp_rect
			(start -0.925 0.47)
			(end 0.925 -0.47)
			(stroke
				(width 0.05)
				(type default)
			)
			(fill no)
			(layer "B.CrtYd")
		)
		(fp_rect
			(start -0.5 0.25)
			(end 0.5 -0.25)
			(stroke
				(width 0.15)
				(type solid)
			)
			(fill no)
			(layer "B.Fab")
		)
		(pad "1" smd roundrect
			(at -0.48 0 270)
			(size 0.59 0.64)
			(layers "B.Cu" "B.Mask" "B.Paste")
			(roundrect_rratio 0.25)
			(net 1307 "/USER_IO.LED_BLUE")
			(pintype "passive")
		)
		(pad "2" smd roundrect
			(at 0.48 0 270)
			(size 0.59 0.64)
			(layers "B.Cu" "B.Mask" "B.Paste")
			(roundrect_rratio 0.25)
			(net 1 "GND")
			(pintype "passive")
		)
	)
	(footprint "antmicro-footprints:SOT-23-5"
		(layer "B.Cu")
		(at 186.55 184.8 -90)
		(property "Reference" "U44"
			(at -1.075 -2.7 90)
			(layer "B.SilkS")
			(effects
				(font
					(size 0.7 0.7)
					(thickness 0.15)
				)
				(justify left bottom mirror)
			)
		)
		(property "Value" "NCP718BSN330T1G"
			(at 0.002 -2.799 90)
			(layer "B.Fab")
			(effects
				(font
					(size 0.7 0.7)
					(thickness 0.15)
				)
				(justify left bottom mirror)
			)
		)
		(property "Description" "Linear Voltage Regulator IC Positive Fixed 1 Output 300mA TSOT-23-5"
			(at 0 0 270)
			(layer "F.Fab")
			(hide yes)
			(effects
				(font
					(size 1.27 1.27)
					(thickness 0.15)
				)
			)
		)
		(property "Author" "Antmicro"
			(at 1.75 371.35 0)
			(layer "B.Fab")
			(hide yes)
			(effects
				(font
					(size 1 1)
					(thickness 0.15)
				)
				(justify mirror)
			)
		)
		(property "License" "Apache-2.0"
			(at 1.75 371.35 0)
			(layer "B.Fab")
			(hide yes)
			(effects
				(font
					(size 1 1)
					(thickness 0.15)
				)
				(justify mirror)
			)
		)
		(property "MPN" "NCP718BSN330T1G"
			(at 1.75 371.35 0)
			(layer "B.Fab")
			(hide yes)
			(effects
				(font
					(size 1 1)
					(thickness 0.15)
				)
				(justify mirror)
			)
		)
		(property "Manufacturer" "ON Semiconductor"
			(at 1.75 371.35 0)
			(layer "B.Fab")
			(hide yes)
			(effects
				(font
					(size 1 1)
					(thickness 0.15)
				)
				(justify mirror)
			)
		)
		(sheetname "DC-DC Converters")
		(sheetfile "dc-dc.kicad_sch")
		(attr smd)
		(fp_line
			(start -0.8 1.6)
			(end -0.5 1.6)
			(stroke
				(width 0.15)
				(type solid)
			)
			(layer "B.SilkS")
		)
		(fp_line
			(start -0.8 1.6)
			(end -0.8 1.3)
			(stroke
				(width 0.15)
				(type solid)
			)
			(layer "B.SilkS")
		)
		(fp_line
			(start 0.8 1.6)
			(end 0.5 1.6)
			(stroke
				(width 0.15)
				(type solid)
			)
			(layer "B.SilkS")
		)
		(fp_line
			(start 0.8 1.3)
			(end 0.8 1.6)
			(stroke
				(width 0.15)
				(type solid)
			)
			(layer "B.SilkS")
		)
		(fp_line
			(start 0.8 -0.55)
			(end 0.8 0.55)
			(stroke
				(width 0.15)
				(type solid)
			)
			(layer "B.SilkS")
		)
		(fp_line
			(start 0.8 -1.3)
			(end 0.8 -1.599)
			(stroke
				(width 0.15)
				(type solid)
			)
			(layer "B.SilkS")
		)
		(fp_line
			(start 0.8 -1.599)
			(end 0.549 -1.599)
			(stroke
				(width 0.15)
				(type solid)
			)
			(layer "B.SilkS")
		)
		(fp_line
			(start -0.85 -1.6)
			(end -0.85 -1.301)
			(stroke
				(width 0.15)
				(type solid)
			)
			(layer "B.SilkS")
		)
		(fp_line
			(start -0.55 -1.6)
			(end -0.85 -1.6)
			(stroke
				(width 0.15)
				(type solid)
			)
			(layer "B.SilkS")
		)
		(fp_circle
			(center -1.25 1.5)
			(end -1.2 1.5)
			(stroke
				(width 0.15)
				(type solid)
			)
			(fill yes)
			(layer "B.SilkS")
		)
		(fp_rect
			(start 1.9 1.76)
			(end -1.9 -1.75)
			(stroke
				(width 0.05)
				(type solid)
			)
			(fill no)
			(layer "B.CrtYd")
		)
		(fp_line
			(start -0.398 1.526)
			(end -0.874 1.05)
			(stroke
				(width 0.15)
				(type solid)
			)
			(layer "B.Fab")
		)
		(fp_rect
			(start 0.874 -1.523)
			(end -0.873 1.525)
			(stroke
				(width 0.15)
				(type solid)
			)
			(fill no)
			(layer "B.Fab")
		)
		(pad "1" smd rect
			(at -1.351 0.951)
			(size 0.55 1)
			(layers "B.Cu" "B.Mask" "B.Paste")
			(net 702 "VDC")
			(pinfunction "VIN")
			(pintype "passive")
		)
		(pad "2" smd rect
			(at -1.351 0)
			(size 0.55 1)
			(layers "B.Cu" "B.Mask" "B.Paste")
			(net 1 "GND")
			(pinfunction "GND")
			(pintype "passive")
		)
		(pad "3" smd rect
			(at -1.351 -0.949)
			(size 0.55 1)
			(layers "B.Cu" "B.Mask" "B.Paste")
			(net 702 "VDC")
			(pinfunction "EN")
			(pintype "passive")
		)
		(pad "4" smd rect
			(at 1.35 -0.949)
			(size 0.55 1)
			(layers "B.Cu" "B.Mask" "B.Paste")
			(net 1411 "unconnected-(U44-NC-Pad4)")
			(pinfunction "NC")
			(pintype "no_connect")
		)
		(pad "5" smd rect
			(at 1.35 0.951)
			(size 0.55 1)
			(layers "B.Cu" "B.Mask" "B.Paste")
			(net 37 "+3V3_AON")
			(pinfunction "VOUT")
			(pintype "passive")
		)
	)
)
